# BASEBOARD_FAB2 (Tioga Pass) — schematic netlist excerpt (pin names and nets, part order shuffled) for the footprints in the layout excerpt that follows; sources: Cadence DE-HDL packaged netlist, KiCad conversion of Wiwynn_Tioga_Pass_MB.brd

C9L13  CAP  10UF 16V 10% X6S  pkg 0805  page 227 : A = VR_FET_SW_P12V_STBY_PVDDQ_KLM ; B = GND
C9N2  CAP  0.22UF 16V 10% X7R  pkg 0402  page 182 : A = P3E_CPU1_PE3_MP_C_TXN<10> ; B = P3E_CPU1_PE3_MP_TXN<10>
C1M8  CAP  0.22UF 16V 10% X7R  pkg 0402  page 106 : A = P3E_CPU0_PE3_OCP_TXP<14> ; B = P3E_OCP_CPU0_PE3_C_TXP<14>

(kicad_pcb
	(version 20260206)
	(generator "pcbnew")
	(generator_version "10.0")
	(general
		(thickness 1.6)
		(legacy_teardrops no)
	)
	(paper "A4")
	(title_block
		(title "Wiwynn_Tioga_Pass_MB.brd")
		(comment 1 "Tioga Pass / footprints 2564-2566 of 4770")
	)
	(layers
		(0 "F.Cu" signal "TOP")
		(4 "In1.Cu" signal "L2GND")
		(6 "In2.Cu" signal "L3")
		(8 "In3.Cu" signal "L4GND")
		(10 "In4.Cu" signal "L5")
		(12 "In5.Cu" signal "L6GND")
		(14 "In6.Cu" signal "L7VCC")
		(16 "In7.Cu" signal "L8VCC")
		(18 "In8.Cu" signal "L9GND")
		(20 "In9.Cu" signal "L10")
		(22 "In10.Cu" signal "L11GND")
		(24 "In11.Cu" signal "L12")
		(26 "In12.Cu" signal "L13GND")
		(2 "B.Cu" signal "BOTTOM")
		(9 "F.Adhes" user "F.Adhesive")
		(11 "B.Adhes" user "B.Adhesive")
		(13 "F.Paste" user "Package Geometry/Pastemask Top")
		(15 "B.Paste" user "Package Geometry/Pastemask Bottom")
		(5 "F.SilkS" user "Ref Des/Silkscreen Top")
		(7 "B.SilkS" user "Ref Des/Silkscreen Bottom")
		(1 "F.Mask" user "Board Geometry/Soldermask Top")
		(3 "B.Mask" user "Board Geometry/Soldermask Bottom")
		(17 "Dwgs.User" user "User.Drawings")
		(19 "Cmts.User" user "User.Comments")
		(21 "Eco1.User" user "User.Eco1")
		(23 "Eco2.User" user "User.Eco2")
		(25 "Edge.Cuts" user "Board Geometry/Outline")
		(27 "Margin" user)
		(31 "F.CrtYd" user "Package Geometry/Place Bound Top")
		(29 "B.CrtYd" user "Package Geometry/Place Bound Bottom")
		(35 "F.Fab" user "Ref Des/Assembly Top")
		(33 "B.Fab" user "Ref Des/Assembly Bottom")
	)
	(footprint ""
		(layer "B.Cu")
		(at 463.042 -116.49202)
		(property "Reference" "C1M8"
			(at 0 0 0)
			(layer "B.SilkS")
			(hide yes)
			(effects
				(font
					(size 1.27 1.27)
				)
				(justify mirror)
			)
		)
		(property "Value" ""
			(at 0 0 0)
			(layer "B.Fab")
			(effects
				(font
					(size 1.27 1.27)
				)
				(justify mirror)
			)
		)
		(duplicate_pad_numbers_are_jumpers no)
		(fp_rect
			(start -0.3048 0.9906)
			(end 0.3048 -0.1016)
			(stroke
				(width 0)
				(type default)
			)
			(fill no)
			(layer "B.CrtYd")
		)
		(fp_line
			(start -0.3048 -0.1016)
			(end 0.3048 -0.1016)
			(stroke
				(width 0.1)
				(type default)
			)
			(layer "B.Fab")
		)
		(fp_line
			(start -0.3048 0.9906)
			(end -0.3048 -0.1016)
			(stroke
				(width 0.1)
				(type default)
			)
			(layer "B.Fab")
		)
		(fp_line
			(start 0.3048 -0.1016)
			(end 0.3048 0.9906)
			(stroke
				(width 0.1)
				(type default)
			)
			(layer "B.Fab")
		)
		(fp_line
			(start 0.3048 0.9906)
			(end -0.3048 0.9906)
			(stroke
				(width 0.1)
				(type default)
			)
			(layer "B.Fab")
		)
		(pad "1" smd rect
			(at 0 0 180)
			(size 0.508 0.508)
			(layers "B.Cu" "B.Mask" "B.Paste")
			(net "P3E_CPU0_PE3_OCP_TXP<14>")
		)
		(pad "2" smd rect
			(at 0 0.889 180)
			(size 0.508 0.508)
			(layers "B.Cu" "B.Mask" "B.Paste")
			(net "P3E_OCP_CPU0_PE3_C_TXP<14>")
		)
		(zone
			(layer "B.Cu")
			(hatch none 0.5)
			(connect_pads
				(clearance 0)
			)
			(min_thickness 0.25)
			(keepout
				(tracks allowed)
				(vias not_allowed)
				(pads allowed)
				(copperpour not_allowed)
				(footprints allowed)
			)
			(placement
				(enabled no)
				(sheetname "")
			)
			(fill
				(thermal_gap 0.5)
				(thermal_bridge_width 0.5)
				(island_removal_mode 0)
			)
			(polygon
				(pts
					(xy 462.788 -115.85702) (xy 463.296 -115.85702) (xy 463.296 -116.23802) (xy 462.788 -116.23802)
				)
			)
		)
		(zone
			(layer "B.Cu")
			(hatch none 0.5)
			(connect_pads
				(clearance 0)
			)
			(min_thickness 0.25)
			(keepout
				(tracks not_allowed)
				(vias allowed)
				(pads allowed)
				(copperpour not_allowed)
				(footprints allowed)
			)
			(placement
				(enabled no)
				(sheetname "")
			)
			(fill
				(thermal_gap 0.5)
				(thermal_bridge_width 0.5)
				(island_removal_mode 0)
			)
			(polygon
				(pts
					(xy 462.788 -115.85702) (xy 463.296 -115.85702) (xy 463.296 -116.23802) (xy 462.788 -116.23802)
				)
			)
		)
	)
	(footprint ""
		(layer "B.Cu")
		(at 1.3462 -146.685 90)
		(property "Reference" "C9L13"
			(at 0 0 90)
			(layer "B.SilkS")
			(hide yes)
			(effects
				(font
					(size 1.27 1.27)
				)
				(justify mirror)
			)
		)
		(property "Value" ""
			(at 0 0 90)
			(layer "B.Fab")
			(effects
				(font
					(size 1.27 1.27)
				)
				(justify mirror)
			)
		)
		(duplicate_pad_numbers_are_jumpers no)
		(fp_rect
			(start -0.7239 -0.2159)
			(end 0.7239 1.9939)
			(stroke
				(width 0)
				(type default)
			)
			(fill no)
			(layer "B.CrtYd")
		)
		(fp_line
			(start 0.7239 -0.2159)
			(end 0.7239 1.9939)
			(stroke
				(width 0.1)
				(type default)
			)
			(layer "B.Fab")
		)
		(fp_line
			(start -0.7239 -0.2159)
			(end 0.7239 -0.2159)
			(stroke
				(width 0.1)
				(type default)
			)
			(layer "B.Fab")
		)
		(fp_line
			(start 0.7239 1.9939)
			(end -0.7239 1.9939)
			(stroke
				(width 0.1)
				(type default)
			)
			(layer "B.Fab")
		)
		(fp_line
			(start -0.7239 1.9939)
			(end -0.7239 -0.2159)
			(stroke
				(width 0.1)
				(type default)
			)
			(layer "B.Fab")
		)
		(pad "1" smd rect
			(at 0 0 270)
			(size 1.27 1.016)
			(layers "B.Cu" "B.Mask" "B.Paste")
			(net "VR_FET_SW_P12V_STBY_PVDDQ_KLM")
		)
		(pad "2" smd rect
			(at 0 1.778 270)
			(size 1.27 1.016)
			(layers "B.Cu" "B.Mask" "B.Paste")
			(net "GND")
		)
		(zone
			(layer "B.Cu")
			(hatch none 0.5)
			(connect_pads
				(clearance 0)
			)
			(min_thickness 0.25)
			(keepout
				(tracks not_allowed)
				(vias allowed)
				(pads allowed)
				(copperpour not_allowed)
				(footprints allowed)
			)
			(placement
				(enabled no)
				(sheetname "")
			)
			(fill
				(thermal_gap 0.5)
				(thermal_bridge_width 0.5)
				(island_removal_mode 0)
			)
			(polygon
				(pts
					(xy 1.8542 -146.05) (xy 2.6162 -146.05) (xy 2.6162 -147.32) (xy 1.8542 -147.32)
				)
			)
		)
	)
	(footprint ""
		(layer "B.Cu")
		(at 16.82242 -107.94492 90)
		(property "Reference" "C9N2"
			(at 0 0 90)
			(layer "B.SilkS")
			(hide yes)
			(effects
				(font
					(size 1.27 1.27)
				)
				(justify mirror)
			)
		)
		(property "Value" ""
			(at 0 0 90)
			(layer "B.Fab")
			(effects
				(font
					(size 1.27 1.27)
				)
				(justify mirror)
			)
		)
		(duplicate_pad_numbers_are_jumpers no)
		(fp_poly
			(pts
				(xy -0.3048 -0.1016) (xy -0.3048 0.9906) (xy 0.3048 0.9906) (xy 0.3048 -0.1016)
			)
			(stroke
				(width 0)
				(type default)
			)
			(fill no)
			(layer "B.CrtYd")
		)
		(fp_line
			(start 0.3048 -0.1016)
			(end 0.3048 0.9906)
			(stroke
				(width 0.1)
				(type default)
			)
			(layer "B.Fab")
		)
		(fp_line
			(start -0.3048 -0.1016)
			(end 0.3048 -0.1016)
			(stroke
				(width 0.1)
				(type default)
			)
			(layer "B.Fab")
		)
		(fp_line
			(start 0.3048 0.9906)
			(end -0.3048 0.9906)
			(stroke
				(width 0.1)
				(type default)
			)
			(layer "B.Fab")
		)
		(fp_line
			(start -0.3048 0.9906)
			(end -0.3048 -0.1016)
			(stroke
				(width 0.1)
				(type default)
			)
			(layer "B.Fab")
		)
		(pad "1" smd rect
			(at 0 0 270)
			(size 0.508 0.508)
			(layers "B.Cu" "B.Mask" "B.Paste")
			(net "P3E_CPU1_PE3_MP_C_TXN<10>")
		)
		(pad "2" smd rect
			(at 0 0.889 270)
			(size 0.508 0.508)
			(layers "B.Cu" "B.Mask" "B.Paste")
			(net "P3E_CPU1_PE3_MP_TXN<10>")
		)
		(zone
			(layer "B.Cu")
			(hatch none 0.5)
			(connect_pads
				(clearance 0)
			)
			(min_thickness 0.25)
			(keepout
				(tracks allowed)
				(vias not_allowed)
				(pads allowed)
				(copperpour not_allowed)
				(footprints allowed)
			)
			(placement
				(enabled no)
				(sheetname "")
			)
			(fill
				(thermal_gap 0.5)
				(thermal_bridge_width 0.5)
				(island_removal_mode 0)
			)
			(polygon
				(pts
					(xy 17.07642 -108.19892) (xy 17.07642 -107.69092) (xy 17.45742 -107.69092) (xy 17.45742 -108.19892)
				)
			)
		)
		(zone
			(layer "B.Cu")
			(hatch none 0.5)
			(connect_pads
				(clearance 0)
			)
			(min_thickness 0.25)
			(keepout
				(tracks not_allowed)
				(vias allowed)
				(pads allowed)
				(copperpour not_allowed)
				(footprints allowed)
			)
			(placement
				(enabled no)
				(sheetname "")
			)
			(fill
				(thermal_gap 0.5)
				(thermal_bridge_width 0.5)
				(island_removal_mode 0)
			)
			(polygon
				(pts
					(xy 17.45742 -108.19892) (xy 17.45742 -107.69092) (xy 17.07642 -107.69092) (xy 17.07642 -108.19892)
				)
			)
		)
	)
)
